(kicad_pcb
	(version 20260206)
	(generator "pcbnew")
	(generator_version "10.0")
	(general
		(thickness 1.6)
		(legacy_teardrops no)
	)
	(paper "A4")
	(title_block
		(title "9054_F0T_PDB_BD_GPU_F_V04_1213_1550_OCP.brd")
		(comment 1 "Grand Teton / footprints 73-79 of 608")
	)
	(layers
		(0 "F.Cu" signal "TOP")
		(4 "In1.Cu" signal "GND")
		(6 "In2.Cu" signal "IN1")
		(8 "In3.Cu" signal "GND1")
		(10 "In4.Cu" signal "VCC")
		(12 "In5.Cu" signal "VCC1")
		(14 "In6.Cu" signal "GND2")
		(16 "In7.Cu" signal "IN2")
		(18 "In8.Cu" signal "GND3")
		(2 "B.Cu" signal "BOTTOM")
		(9 "F.Adhes" user "F.Adhesive")
		(11 "B.Adhes" user "B.Adhesive")
		(13 "F.Paste" user "Package Geometry/Pastemask Top")
		(15 "B.Paste" user "Package Geometry/Pastemask Bottom")
		(5 "F.SilkS" user "Ref Des/Silkscreen Top")
		(7 "B.SilkS" user "Ref Des/Silkscreen Bottom")
		(1 "F.Mask" user "Board Geometry/Soldermask Top")
		(3 "B.Mask" user "Board Geometry/Soldermask Bottom")
		(17 "Dwgs.User" user "User.Drawings")
		(19 "Cmts.User" user "User.Comments")
		(21 "Eco1.User" user "User.Eco1")
		(23 "Eco2.User" user "User.Eco2")
		(25 "Edge.Cuts" user "Board Geometry/Outline")
		(27 "Margin" user)
		(31 "F.CrtYd" user "Package Geometry/Place Bound Top")
		(29 "B.CrtYd" user "Package Geometry/Place Bound Bottom")
		(35 "F.Fab" user "Ref Des/Assembly Top")
		(33 "B.Fab" user "Ref Des/Assembly Bottom")
	)
	(footprint ""
		(layer "F.Cu")
		(at 281.0764 -75.184 180)
		(property "Reference" "PR37"
			(at 0 0 180)
			(layer "F.SilkS")
			(hide yes)
			(effects
				(font
					(size 1.27 1.27)
				)
			)
		)
		(property "Value" ""
			(at 0 0 180)
			(layer "F.Fab")
			(effects
				(font
					(size 1.27 1.27)
				)
			)
		)
		(duplicate_pad_numbers_are_jumpers no)
		(fp_line
			(start 0.7874 0.4064)
			(end -0.7874 0.4064)
			(stroke
				(width 0.1524)
				(type default)
			)
			(layer "F.SilkS")
		)
		(fp_line
			(start 0.7874 -0.4064)
			(end 0.7874 0.4064)
			(stroke
				(width 0.1524)
				(type default)
			)
			(layer "F.SilkS")
		)
		(fp_line
			(start -0.7874 0.4064)
			(end -0.7874 -0.4064)
			(stroke
				(width 0.1524)
				(type default)
			)
			(layer "F.SilkS")
		)
		(fp_line
			(start -0.7874 -0.4064)
			(end 0.7874 -0.4064)
			(stroke
				(width 0.1524)
				(type default)
			)
			(layer "F.SilkS")
		)
		(fp_line
			(start 0.67945 0.3048)
			(end 0.120396 0.3048)
			(stroke
				(width 0.1)
				(type default)
			)
			(layer "F.Fab")
		)
		(fp_line
			(start 0.67945 -0.3048)
			(end 0.67945 0.3048)
			(stroke
				(width 0.1)
				(type default)
			)
			(layer "F.Fab")
		)
		(fp_line
			(start 0.12065 -0.2794)
			(end 0.12065 -0.3048)
			(stroke
				(width 0.1)
				(type default)
			)
			(layer "F.Fab")
		)
		(fp_line
			(start 0.12065 -0.3048)
			(end 0.67945 -0.3048)
			(stroke
				(width 0.1)
				(type default)
			)
			(layer "F.Fab")
		)
		(fp_line
			(start 0.120396 0.3048)
			(end 0.120396 0.2794)
			(stroke
				(width 0.1)
				(type default)
			)
			(layer "F.Fab")
		)
		(fp_line
			(start 0.120396 0.2794)
			(end -0.12065 0.2794)
			(stroke
				(width 0.1)
				(type default)
			)
			(layer "F.Fab")
		)
		(fp_line
			(start -0.12065 0.3048)
			(end -0.67945 0.3048)
			(stroke
				(width 0.1)
				(type default)
			)
			(layer "F.Fab")
		)
		(fp_line
			(start -0.12065 0.2794)
			(end -0.12065 0.3048)
			(stroke
				(width 0.1)
				(type default)
			)
			(layer "F.Fab")
		)
		(fp_line
			(start -0.12065 -0.2794)
			(end 0.12065 -0.2794)
			(stroke
				(width 0.1)
				(type default)
			)
			(layer "F.Fab")
		)
		(fp_line
			(start -0.12065 -0.305054)
			(end -0.12065 -0.2794)
			(stroke
				(width 0.1)
				(type default)
			)
			(layer "F.Fab")
		)
		(fp_line
			(start -0.67945 0.3048)
			(end -0.67945 -0.305054)
			(stroke
				(width 0.1)
				(type default)
			)
			(layer "F.Fab")
		)
		(fp_line
			(start -0.67945 -0.305054)
			(end -0.12065 -0.305054)
			(stroke
				(width 0.1)
				(type default)
			)
			(layer "F.Fab")
		)
		(pad "1" smd circle
			(at -0.40005 0 180)
			(size 0 0)
			(layers "F.Cu" "F.Mask" "F.Paste")
			(net "P52V_HS1_EFAULT")
		)
		(pad "2" smd circle
			(at 0.40005 0 180)
			(size 0 0)
			(layers "F.Cu" "F.Mask" "F.Paste")
			(net "GND_FIELD_SIGNAL")
		)
	)
	(footprint ""
		(layer "F.Cu")
		(at 427.228 -43.18)
		(property "Reference" "R100"
			(at 0 0 0)
			(layer "F.SilkS")
			(hide yes)
			(effects
				(font
					(size 1.27 1.27)
				)
			)
		)
		(property "Value" ""
			(at 0 0 0)
			(layer "F.Fab")
			(effects
				(font
					(size 1.27 1.27)
				)
			)
		)
		(duplicate_pad_numbers_are_jumpers no)
		(fp_line
			(start -0.7874 -0.4064)
			(end 0.7874 -0.4064)
			(stroke
				(width 0.1524)
				(type default)
			)
			(layer "F.SilkS")
		)
		(fp_line
			(start -0.7874 0.4064)
			(end -0.7874 -0.4064)
			(stroke
				(width 0.1524)
				(type default)
			)
			(layer "F.SilkS")
		)
		(fp_line
			(start 0.7874 -0.4064)
			(end 0.7874 0.4064)
			(stroke
				(width 0.1524)
				(type default)
			)
			(layer "F.SilkS")
		)
		(fp_line
			(start 0.7874 0.4064)
			(end -0.7874 0.4064)
			(stroke
				(width 0.1524)
				(type default)
			)
			(layer "F.SilkS")
		)
		(fp_line
			(start -0.67945 -0.305054)
			(end -0.12065 -0.305054)
			(stroke
				(width 0.1)
				(type default)
			)
			(layer "F.Fab")
		)
		(fp_line
			(start -0.67945 0.3048)
			(end -0.67945 -0.305054)
			(stroke
				(width 0.1)
				(type default)
			)
			(layer "F.Fab")
		)
		(fp_line
			(start -0.12065 -0.305054)
			(end -0.12065 -0.2794)
			(stroke
				(width 0.1)
				(type default)
			)
			(layer "F.Fab")
		)
		(fp_line
			(start -0.12065 -0.2794)
			(end 0.12065 -0.2794)
			(stroke
				(width 0.1)
				(type default)
			)
			(layer "F.Fab")
		)
		(fp_line
			(start -0.12065 0.2794)
			(end -0.12065 0.3048)
			(stroke
				(width 0.1)
				(type default)
			)
			(layer "F.Fab")
		)
		(fp_line
			(start -0.12065 0.3048)
			(end -0.67945 0.3048)
			(stroke
				(width 0.1)
				(type default)
			)
			(layer "F.Fab")
		)
		(fp_line
			(start 0.120396 0.2794)
			(end -0.12065 0.2794)
			(stroke
				(width 0.1)
				(type default)
			)
			(layer "F.Fab")
		)
		(fp_line
			(start 0.120396 0.3048)
			(end 0.120396 0.2794)
			(stroke
				(width 0.1)
				(type default)
			)
			(layer "F.Fab")
		)
		(fp_line
			(start 0.12065 -0.3048)
			(end 0.67945 -0.3048)
			(stroke
				(width 0.1)
				(type default)
			)
			(layer "F.Fab")
		)
		(fp_line
			(start 0.12065 -0.2794)
			(end 0.12065 -0.3048)
			(stroke
				(width 0.1)
				(type default)
			)
			(layer "F.Fab")
		)
		(fp_line
			(start 0.67945 -0.3048)
			(end 0.67945 0.3048)
			(stroke
				(width 0.1)
				(type default)
			)
			(layer "F.Fab")
		)
		(fp_line
			(start 0.67945 0.3048)
			(end 0.120396 0.3048)
			(stroke
				(width 0.1)
				(type default)
			)
			(layer "F.Fab")
		)
		(pad "1" smd circle
			(at -0.40005 0)
			(size 0 0)
			(layers "F.Cu" "F.Mask" "F.Paste")
			(net "SKU_ID_1")
		)
		(pad "2" smd circle
			(at 0.40005 0)
			(size 0 0)
			(layers "F.Cu" "F.Mask" "F.Paste")
			(net "GND")
		)
	)
	(footprint ""
		(layer "F.Cu")
		(at 11.999976 -83.999832 180)
		(property "Reference" "H1"
			(at 0.569976 -5.413502 0)
			(unlocked yes)
			(layer "F.SilkS")
			(effects
				(font
					(size 0.7874 0.5842)
					(thickness 0.1524)
				)
				(justify left)
			)
		)
		(property "Value" ""
			(at 0 0 180)
			(layer "F.Fab")
			(effects
				(font
					(size 1.27 1.27)
				)
			)
		)
		(duplicate_pad_numbers_are_jumpers no)
		(pad "1" thru_hole oval
			(at 0 0 180)
			(size 9.017 14.0208)
			(drill 3.0226
				(offset 0 2.499868)
			)
			(layers "*.Cu" "*.Mask")
			(remove_unused_layers no)
			(net "GND")
			(clearance -1.500378)
			(padstack
				(mode front_inner_back)
				(layer "Inner"
					(shape circle)
					(size 0 0)
					(clearance 0)
				)
				(layer "B.Cu"
					(shape oval)
					(size 9.017 14.0208)
					(offset 0 2.499868)
					(clearance -1.500378)
				)
			)
		)
	)
	(footprint ""
		(layer "F.Cu")
		(at 409.956 -43.053)
		(property "Reference" "R5911"
			(at 0 0 0)
			(layer "F.SilkS")
			(hide yes)
			(effects
				(font
					(size 1.27 1.27)
				)
			)
		)
		(property "Value" ""
			(at 0 0 0)
			(layer "F.Fab")
			(effects
				(font
					(size 1.27 1.27)
				)
			)
		)
		(duplicate_pad_numbers_are_jumpers no)
		(fp_line
			(start -0.7874 -0.4064)
			(end 0.7874 -0.4064)
			(stroke
				(width 0.1524)
				(type default)
			)
			(layer "F.SilkS")
		)
		(fp_line
			(start -0.7874 0.4064)
			(end -0.7874 -0.4064)
			(stroke
				(width 0.1524)
				(type default)
			)
			(layer "F.SilkS")
		)
		(fp_line
			(start 0.7874 -0.4064)
			(end 0.7874 0.4064)
			(stroke
				(width 0.1524)
				(type default)
			)
			(layer "F.SilkS")
		)
		(fp_line
			(start 0.7874 0.4064)
			(end -0.7874 0.4064)
			(stroke
				(width 0.1524)
				(type default)
			)
			(layer "F.SilkS")
		)
		(fp_line
			(start -0.67945 -0.305054)
			(end -0.12065 -0.305054)
			(stroke
				(width 0.1)
				(type default)
			)
			(layer "F.Fab")
		)
		(fp_line
			(start -0.67945 0.3048)
			(end -0.67945 -0.305054)
			(stroke
				(width 0.1)
				(type default)
			)
			(layer "F.Fab")
		)
		(fp_line
			(start -0.12065 -0.305054)
			(end -0.12065 -0.2794)
			(stroke
				(width 0.1)
				(type default)
			)
			(layer "F.Fab")
		)
		(fp_line
			(start -0.12065 -0.2794)
			(end 0.12065 -0.2794)
			(stroke
				(width 0.1)
				(type default)
			)
			(layer "F.Fab")
		)
		(fp_line
			(start -0.12065 0.2794)
			(end -0.12065 0.3048)
			(stroke
				(width 0.1)
				(type default)
			)
			(layer "F.Fab")
		)
		(fp_line
			(start -0.12065 0.3048)
			(end -0.67945 0.3048)
			(stroke
				(width 0.1)
				(type default)
			)
			(layer "F.Fab")
		)
		(fp_line
			(start 0.120396 0.2794)
			(end -0.12065 0.2794)
			(stroke
				(width 0.1)
				(type default)
			)
			(layer "F.Fab")
		)
		(fp_line
			(start 0.120396 0.3048)
			(end 0.120396 0.2794)
			(stroke
				(width 0.1)
				(type default)
			)
			(layer "F.Fab")
		)
		(fp_line
			(start 0.12065 -0.3048)
			(end 0.67945 -0.3048)
			(stroke
				(width 0.1)
				(type default)
			)
			(layer "F.Fab")
		)
		(fp_line
			(start 0.12065 -0.2794)
			(end 0.12065 -0.3048)
			(stroke
				(width 0.1)
				(type default)
			)
			(layer "F.Fab")
		)
		(fp_line
			(start 0.67945 -0.3048)
			(end 0.67945 0.3048)
			(stroke
				(width 0.1)
				(type default)
			)
			(layer "F.Fab")
		)
		(fp_line
			(start 0.67945 0.3048)
			(end 0.120396 0.3048)
			(stroke
				(width 0.1)
				(type default)
			)
			(layer "F.Fab")
		)
		(pad "1" smd circle
			(at -0.40005 0)
			(size 0 0)
			(layers "F.Cu" "F.Mask" "F.Paste")
			(net "P3V3_AUX")
		)
		(pad "2" smd circle
			(at 0.40005 0)
			(size 0 0)
			(layers "F.Cu" "F.Mask" "F.Paste")
			(net "PRSNT_FAN_BP0_R_N")
		)
	)
	(footprint ""
		(layer "F.Cu")
		(at 177.927 -45.212 180)
		(property "Reference" "R384"
			(at 0 0 180)
			(layer "F.SilkS")
			(hide yes)
			(effects
				(font
					(size 1.27 1.27)
				)
			)
		)
		(property "Value" ""
			(at 0 0 180)
			(layer "F.Fab")
			(effects
				(font
					(size 1.27 1.27)
				)
			)
		)
		(duplicate_pad_numbers_are_jumpers no)
		(fp_line
			(start 1.651 0.8382)
			(end -1.651 0.8382)
			(stroke
				(width 0.1524)
				(type default)
			)
			(layer "F.SilkS")
		)
		(fp_line
			(start 1.651 -0.8382)
			(end 1.651 0.8382)
			(stroke
				(width 0.1524)
				(type default)
			)
			(layer "F.SilkS")
		)
		(fp_line
			(start -1.651 0.8382)
			(end -1.651 -0.8382)
			(stroke
				(width 0.1524)
				(type default)
			)
			(layer "F.SilkS")
		)
		(fp_line
			(start -1.651 -0.8382)
			(end 1.651 -0.8382)
			(stroke
				(width 0.1524)
				(type default)
			)
			(layer "F.SilkS")
		)
		(fp_line
			(start 1.560576 0.7366)
			(end 1.560576 -0.7366)
			(stroke
				(width 0.1)
				(type default)
			)
			(layer "F.Fab")
		)
		(fp_line
			(start 1.560576 -0.7366)
			(end 1.524 -0.7366)
			(stroke
				(width 0.1)
				(type default)
			)
			(layer "F.Fab")
		)
		(fp_line
			(start 1.524 0.7366)
			(end 1.560576 0.7366)
			(stroke
				(width 0.1)
				(type default)
			)
			(layer "F.Fab")
		)
		(fp_line
			(start 1.524 -0.7366)
			(end -1.524 -0.7366)
			(stroke
				(width 0.1)
				(type default)
			)
			(layer "F.Fab")
		)
		(fp_line
			(start -1.524 0.7366)
			(end 1.524 0.7366)
			(stroke
				(width 0.1)
				(type default)
			)
			(layer "F.Fab")
		)
		(fp_line
			(start -1.524 -0.7366)
			(end -1.559814 -0.7366)
			(stroke
				(width 0.1)
				(type default)
			)
			(layer "F.Fab")
		)
		(fp_line
			(start -1.559814 0.7366)
			(end -1.524 0.7366)
			(stroke
				(width 0.1)
				(type default)
			)
			(layer "F.Fab")
		)
		(fp_line
			(start -1.559814 -0.7366)
			(end -1.559814 0.7366)
			(stroke
				(width 0.1)
				(type default)
			)
			(layer "F.Fab")
		)
		(pad "1" smd rect
			(at -0.94996 0)
			(size 1.1176 1.3716)
			(layers "F.Cu" "F.Mask" "F.Paste")
			(net "P52V_2_FUSE_1")
		)
		(pad "2" smd rect
			(at 0.94996 0)
			(size 1.1176 1.3716)
			(layers "F.Cu" "F.Mask" "F.Paste")
			(net "GPU_HSC2_BUF_EN_N")
		)
	)
	(footprint ""
		(layer "F.Cu")
		(at 430.276 -45.974 180)
		(property "Reference" "R53"
			(at 0 0 180)
			(layer "F.SilkS")
			(hide yes)
			(effects
				(font
					(size 1.27 1.27)
				)
			)
		)
		(property "Value" ""
			(at 0 0 180)
			(layer "F.Fab")
			(effects
				(font
					(size 1.27 1.27)
				)
			)
		)
		(duplicate_pad_numbers_are_jumpers no)
		(fp_line
			(start 0.7874 0.4064)
			(end -0.7874 0.4064)
			(stroke
				(width 0.1524)
				(type default)
			)
			(layer "F.SilkS")
		)
		(fp_line
			(start 0.7874 -0.4064)
			(end 0.7874 0.4064)
			(stroke
				(width 0.1524)
				(type default)
			)
			(layer "F.SilkS")
		)
		(fp_line
			(start -0.7874 0.4064)
			(end -0.7874 -0.4064)
			(stroke
				(width 0.1524)
				(type default)
			)
			(layer "F.SilkS")
		)
		(fp_line
			(start -0.7874 -0.4064)
			(end 0.7874 -0.4064)
			(stroke
				(width 0.1524)
				(type default)
			)
			(layer "F.SilkS")
		)
		(fp_line
			(start 0.67945 0.3048)
			(end 0.120396 0.3048)
			(stroke
				(width 0.1)
				(type default)
			)
			(layer "F.Fab")
		)
		(fp_line
			(start 0.67945 -0.3048)
			(end 0.67945 0.3048)
			(stroke
				(width 0.1)
				(type default)
			)
			(layer "F.Fab")
		)
		(fp_line
			(start 0.12065 -0.2794)
			(end 0.12065 -0.3048)
			(stroke
				(width 0.1)
				(type default)
			)
			(layer "F.Fab")
		)
		(fp_line
			(start 0.12065 -0.3048)
			(end 0.67945 -0.3048)
			(stroke
				(width 0.1)
				(type default)
			)
			(layer "F.Fab")
		)
		(fp_line
			(start 0.120396 0.3048)
			(end 0.120396 0.2794)
			(stroke
				(width 0.1)
				(type default)
			)
			(layer "F.Fab")
		)
		(fp_line
			(start 0.120396 0.2794)
			(end -0.12065 0.2794)
			(stroke
				(width 0.1)
				(type default)
			)
			(layer "F.Fab")
		)
		(fp_line
			(start -0.12065 0.3048)
			(end -0.67945 0.3048)
			(stroke
				(width 0.1)
				(type default)
			)
			(layer "F.Fab")
		)
		(fp_line
			(start -0.12065 0.2794)
			(end -0.12065 0.3048)
			(stroke
				(width 0.1)
				(type default)
			)
			(layer "F.Fab")
		)
		(fp_line
			(start -0.12065 -0.2794)
			(end 0.12065 -0.2794)
			(stroke
				(width 0.1)
				(type default)
			)
			(layer "F.Fab")
		)
		(fp_line
			(start -0.12065 -0.305054)
			(end -0.12065 -0.2794)
			(stroke
				(width 0.1)
				(type default)
			)
			(layer "F.Fab")
		)
		(fp_line
			(start -0.67945 0.3048)
			(end -0.67945 -0.305054)
			(stroke
				(width 0.1)
				(type default)
			)
			(layer "F.Fab")
		)
		(fp_line
			(start -0.67945 -0.305054)
			(end -0.12065 -0.305054)
			(stroke
				(width 0.1)
				(type default)
			)
			(layer "F.Fab")
		)
		(pad "1" smd circle
			(at -0.40005 0 180)
			(size 0 0)
			(layers "F.Cu" "F.Mask" "F.Paste")
			(net "P3V3_AUX")
		)
		(pad "2" smd circle
			(at 0.40005 0 180)
			(size 0 0)
			(layers "F.Cu" "F.Mask" "F.Paste")
			(net "PCA9555_A0")
		)
	)
	(footprint ""
		(layer "F.Cu")
		(at 283.845 -76.327)
		(property "Reference" "PC11"
			(at 0 0 0)
			(layer "F.SilkS")
			(hide yes)
			(effects
				(font
					(size 1.27 1.27)
				)
			)
		)
		(property "Value" ""
			(at 0 0 0)
			(layer "F.Fab")
			(effects
				(font
					(size 1.27 1.27)
				)
			)
		)
		(duplicate_pad_numbers_are_jumpers no)
		(fp_line
			(start -1.2954 -0.5842)
			(end 1.2954 -0.5842)
			(stroke
				(width 0.1524)
				(type default)
			)
			(layer "F.SilkS")
		)
		(fp_line
			(start -1.2954 0.5842)
			(end -1.2954 -0.5842)
			(stroke
				(width 0.1524)
				(type default)
			)
			(layer "F.SilkS")
		)
		(fp_line
			(start 1.2954 -0.5842)
			(end 1.2954 0.5842)
			(stroke
				(width 0.1524)
				(type default)
			)
			(layer "F.SilkS")
		)
		(fp_line
			(start 1.2954 0.5842)
			(end -1.2954 0.5842)
			(stroke
				(width 0.1524)
				(type default)
			)
			(layer "F.SilkS")
		)
		(fp_line
			(start -1.1938 -0.4064)
			(end -0.8636 -0.4064)
			(stroke
				(width 0.1)
				(type default)
			)
			(layer "F.Fab")
		)
		(fp_line
			(start -1.1938 0.4064)
			(end -1.1938 -0.4064)
			(stroke
				(width 0.1)
				(type default)
			)
			(layer "F.Fab")
		)
		(fp_line
			(start -0.8636 -0.4572)
			(end 0.8636 -0.4572)
			(stroke
				(width 0.1)
				(type default)
			)
			(layer "F.Fab")
		)
		(fp_line
			(start -0.8636 -0.4064)
			(end -0.8636 -0.4572)
			(stroke
				(width 0.1)
				(type default)
			)
			(layer "F.Fab")
		)
		(fp_line
			(start -0.8636 0.4064)
			(end -1.1938 0.4064)
			(stroke
				(width 0.1)
				(type default)
			)
			(layer "F.Fab")
		)
		(fp_line
			(start -0.8636 0.4572)
			(end -0.8636 0.4064)
			(stroke
				(width 0.1)
				(type default)
			)
			(layer "F.Fab")
		)
		(fp_line
			(start 0.8636 -0.4572)
			(end 0.8636 -0.4064)
			(stroke
				(width 0.1)
				(type default)
			)
			(layer "F.Fab")
		)
		(fp_line
			(start 0.8636 -0.4064)
			(end 1.1938 -0.4064)
			(stroke
				(width 0.1)
				(type default)
			)
			(layer "F.Fab")
		)
		(fp_line
			(start 0.8636 0.4064)
			(end 0.8636 0.4572)
			(stroke
				(width 0.1)
				(type default)
			)
			(layer "F.Fab")
		)
		(fp_line
			(start 0.8636 0.4572)
			(end -0.8636 0.4572)
			(stroke
				(width 0.1)
				(type default)
			)
			(layer "F.Fab")
		)
		(fp_line
			(start 1.1938 -0.4064)
			(end 1.1938 0.4064)
			(stroke
				(width 0.1)
				(type default)
			)
			(layer "F.Fab")
		)
		(fp_line
			(start 1.1938 0.4064)
			(end 0.8636 0.4064)
			(stroke
				(width 0.1)
				(type default)
			)
			(layer "F.Fab")
		)
		(pad "1" smd rect
			(at -0.7366 0 270)
			(size 0.7112 0.8128)
			(layers "F.Cu" "F.Mask" "F.Paste")
			(net "P52V_HS1_ESTART")
		)
		(pad "2" smd rect
			(at 0.7366 0 270)
			(size 0.7112 0.8128)
			(layers "F.Cu" "F.Mask" "F.Paste")
			(net "GND_FIELD_SIGNAL")
		)
	)
)
